# T6G (Grand Teton) — schematic netlist excerpt (pin names and nets, part order shuffled) for the footprints in the layout excerpt that follows; sources: Cadence DE-HDL packaged netlist, KiCad conversion of 04192023_DAF0TMB3IC0_F0TG_MB_C_brd_V02_OCP.brd

C6619  Q_CAP_DIFFBUS  DIFF BUS_0.22UF 6.3V 20% X6S  pkg C0201  page 308 : \1\ = P5E_CPU0_P3_TX_BUF_C_DP<11> ; \2\ = P5E_CPU0_P3_TX_BUF_DP<11>
PR6557  Q_RES  499 1% CHIP  pkg 0603LF  page 363 : A = P0V9_CPU0_RT_2D ; B = GND
C2204  Q_CAP  22UF 4V 20% X6S  pkg C0402  page 69 : A = PVDDCR_CPU1_P0 ; B = GND

(kicad_pcb
	(version 20260206)
	(generator "pcbnew")
	(generator_version "10.0")
	(general
		(thickness 1.6)
		(legacy_teardrops no)
	)
	(paper "A4")
	(title_block
		(title "04192023_DAF0TMB3IC0_F0TG_MB_C_brd_V02_OCP.brd")
		(comment 1 "Grand Teton / footprints 8071-8073 of 8354")
	)
	(layers
		(0 "F.Cu" signal "TOP")
		(4 "In1.Cu" signal "GND")
		(6 "In2.Cu" signal "IN1")
		(8 "In3.Cu" signal "GND1")
		(10 "In4.Cu" signal "IN2")
		(12 "In5.Cu" signal "GND2")
		(14 "In6.Cu" signal "IN3")
		(16 "In7.Cu" signal "GND3")
		(18 "In8.Cu" signal "VCC")
		(20 "In9.Cu" signal "VCC1")
		(22 "In10.Cu" signal "GND4")
		(24 "In11.Cu" signal "IN4")
		(26 "In12.Cu" signal "GND5")
		(28 "In13.Cu" signal "IN5")
		(30 "In14.Cu" signal "GND6")
		(32 "In15.Cu" signal "IN6")
		(34 "In16.Cu" signal "GND7")
		(2 "B.Cu" signal "BOTTOM")
		(9 "F.Adhes" user "F.Adhesive")
		(11 "B.Adhes" user "B.Adhesive")
		(13 "F.Paste" user "Package Geometry/Pastemask Top")
		(15 "B.Paste" user "Package Geometry/Pastemask Bottom")
		(5 "F.SilkS" user "Ref Des/Silkscreen Top")
		(7 "B.SilkS" user "Ref Des/Silkscreen Bottom")
		(1 "F.Mask" user "Board Geometry/Soldermask Top")
		(3 "B.Mask" user "Board Geometry/Soldermask Bottom")
		(17 "Dwgs.User" user "User.Drawings")
		(19 "Cmts.User" user "User.Comments")
		(21 "Eco1.User" user "User.Eco1")
		(23 "Eco2.User" user "User.Eco2")
		(25 "Edge.Cuts" user "Board Geometry/Outline")
		(27 "Margin" user)
		(31 "F.CrtYd" user "Package Geometry/Place Bound Top")
		(29 "B.CrtYd" user "Package Geometry/Place Bound Bottom")
		(35 "F.Fab" user "Ref Des/Assembly Top")
		(33 "B.Fab" user "Ref Des/Assembly Bottom")
	)
	(footprint ""
		(layer "B.Cu")
		(at 363.873288 -267.52931)
		(property "Reference" "C2204"
			(at 0 0 0)
			(layer "B.SilkS")
			(hide yes)
			(effects
				(font
					(size 1.27 1.27)
				)
				(justify mirror)
			)
		)
		(property "Value" ""
			(at 0 0 0)
			(layer "B.Fab")
			(effects
				(font
					(size 1.27 1.27)
				)
				(justify mirror)
			)
		)
		(duplicate_pad_numbers_are_jumpers no)
		(fp_line
			(start -0.7874 -0.4064)
			(end -0.7874 0.4064)
			(stroke
				(width 0.1524)
				(type default)
			)
			(layer "B.SilkS")
		)
		(fp_line
			(start -0.7874 0.4064)
			(end 0.7874 0.4064)
			(stroke
				(width 0.1524)
				(type default)
			)
			(layer "B.SilkS")
		)
		(fp_line
			(start 0.7874 -0.4064)
			(end -0.7874 -0.4064)
			(stroke
				(width 0.1524)
				(type default)
			)
			(layer "B.SilkS")
		)
		(fp_line
			(start 0.7874 0.4064)
			(end 0.7874 -0.4064)
			(stroke
				(width 0.1524)
				(type default)
			)
			(layer "B.SilkS")
		)
		(fp_line
			(start -0.67945 -0.3048)
			(end -0.67945 0.3048)
			(stroke
				(width 0.1)
				(type default)
			)
			(layer "B.Fab")
		)
		(fp_line
			(start -0.67945 0.3048)
			(end -0.120396 0.3048)
			(stroke
				(width 0.1)
				(type default)
			)
			(layer "B.Fab")
		)
		(fp_line
			(start -0.12065 -0.3048)
			(end -0.67945 -0.3048)
			(stroke
				(width 0.1)
				(type default)
			)
			(layer "B.Fab")
		)
		(fp_line
			(start -0.12065 -0.2794)
			(end -0.12065 -0.3048)
			(stroke
				(width 0.1)
				(type default)
			)
			(layer "B.Fab")
		)
		(fp_line
			(start -0.120396 0.2794)
			(end 0.12065 0.2794)
			(stroke
				(width 0.1)
				(type default)
			)
			(layer "B.Fab")
		)
		(fp_line
			(start -0.120396 0.3048)
			(end -0.120396 0.2794)
			(stroke
				(width 0.1)
				(type default)
			)
			(layer "B.Fab")
		)
		(fp_line
			(start 0.12065 -0.305054)
			(end 0.12065 -0.2794)
			(stroke
				(width 0.1)
				(type default)
			)
			(layer "B.Fab")
		)
		(fp_line
			(start 0.12065 -0.2794)
			(end -0.12065 -0.2794)
			(stroke
				(width 0.1)
				(type default)
			)
			(layer "B.Fab")
		)
		(fp_line
			(start 0.12065 0.2794)
			(end 0.12065 0.3048)
			(stroke
				(width 0.1)
				(type default)
			)
			(layer "B.Fab")
		)
		(fp_line
			(start 0.12065 0.3048)
			(end 0.67945 0.3048)
			(stroke
				(width 0.1)
				(type default)
			)
			(layer "B.Fab")
		)
		(fp_line
			(start 0.67945 -0.305054)
			(end 0.12065 -0.305054)
			(stroke
				(width 0.1)
				(type default)
			)
			(layer "B.Fab")
		)
		(fp_line
			(start 0.67945 0.3048)
			(end 0.67945 -0.305054)
			(stroke
				(width 0.1)
				(type default)
			)
			(layer "B.Fab")
		)
		(pad "1" smd circle
			(at 0.40005 0 180)
			(size 0 0)
			(layers "B.Cu" "B.Mask" "B.Paste")
			(net "PVDDCR_CPU1_P0")
		)
		(pad "2" smd circle
			(at -0.40005 0 180)
			(size 0 0)
			(layers "B.Cu" "B.Mask" "B.Paste")
			(net "GND")
		)
	)
	(footprint ""
		(layer "B.Cu")
		(at 463.172556 -389.126222 -90)
		(property "Reference" "PR6557"
			(at 0 0 90)
			(layer "B.SilkS")
			(hide yes)
			(effects
				(font
					(size 1.27 1.27)
				)
				(justify mirror)
			)
		)
		(property "Value" ""
			(at 0 0 90)
			(layer "B.Fab")
			(effects
				(font
					(size 1.27 1.27)
				)
				(justify mirror)
			)
		)
		(duplicate_pad_numbers_are_jumpers no)
		(fp_line
			(start -1.2954 0.5842)
			(end 1.2954 0.5842)
			(stroke
				(width 0.1524)
				(type default)
			)
			(layer "B.SilkS")
		)
		(fp_line
			(start 1.2954 0.5842)
			(end 1.2954 -0.5842)
			(stroke
				(width 0.1524)
				(type default)
			)
			(layer "B.SilkS")
		)
		(fp_line
			(start -1.2954 -0.5842)
			(end -1.2954 0.5842)
			(stroke
				(width 0.1524)
				(type default)
			)
			(layer "B.SilkS")
		)
		(fp_line
			(start 1.2954 -0.5842)
			(end -1.2954 -0.5842)
			(stroke
				(width 0.1524)
				(type default)
			)
			(layer "B.SilkS")
		)
		(fp_line
			(start -0.8636 0.4572)
			(end 0.8636 0.4572)
			(stroke
				(width 0.1)
				(type default)
			)
			(layer "B.Fab")
		)
		(fp_line
			(start 0.8636 0.4572)
			(end 0.8636 0.4318)
			(stroke
				(width 0.1)
				(type default)
			)
			(layer "B.Fab")
		)
		(fp_line
			(start 0.8636 0.4318)
			(end 0.8636 0.4064)
			(stroke
				(width 0.1)
				(type default)
			)
			(layer "B.Fab")
		)
		(fp_line
			(start -1.1938 0.4064)
			(end -0.8636 0.4064)
			(stroke
				(width 0.1)
				(type default)
			)
			(layer "B.Fab")
		)
		(fp_line
			(start -0.8636 0.4064)
			(end -0.8636 0.4572)
			(stroke
				(width 0.1)
				(type default)
			)
			(layer "B.Fab")
		)
		(fp_line
			(start 0.8636 0.4064)
			(end 1.1938 0.4064)
			(stroke
				(width 0.1)
				(type default)
			)
			(layer "B.Fab")
		)
		(fp_line
			(start 1.1938 0.4064)
			(end 1.1938 -0.406654)
			(stroke
				(width 0.1)
				(type default)
			)
			(layer "B.Fab")
		)
		(fp_line
			(start -1.1938 -0.406654)
			(end -1.1938 0.4064)
			(stroke
				(width 0.1)
				(type default)
			)
			(layer "B.Fab")
		)
		(fp_line
			(start -0.8636 -0.406654)
			(end -1.1938 -0.406654)
			(stroke
				(width 0.1)
				(type default)
			)
			(layer "B.Fab")
		)
		(fp_line
			(start 0.8636 -0.406654)
			(end 0.8636 -0.4572)
			(stroke
				(width 0.1)
				(type default)
			)
			(layer "B.Fab")
		)
		(fp_line
			(start 1.1938 -0.406654)
			(end 0.8636 -0.406654)
			(stroke
				(width 0.1)
				(type default)
			)
			(layer "B.Fab")
		)
		(fp_line
			(start -0.8636 -0.4572)
			(end -0.8636 -0.406654)
			(stroke
				(width 0.1)
				(type default)
			)
			(layer "B.Fab")
		)
		(fp_line
			(start 0.8636 -0.4572)
			(end -0.8636 -0.4572)
			(stroke
				(width 0.1)
				(type default)
			)
			(layer "B.Fab")
		)
		(pad "1" smd rect
			(at 0.7366 0 180)
			(size 0.7112 0.8128)
			(layers "B.Cu" "B.Mask" "B.Paste")
			(net "P0V9_CPU0_RT_2D")
		)
		(pad "2" smd rect
			(at -0.7366 0 180)
			(size 0.7112 0.8128)
			(layers "B.Cu" "B.Mask" "B.Paste")
			(net "GND")
		)
	)
	(footprint ""
		(layer "B.Cu")
		(at 407.010362 -416.899344 90)
		(property "Reference" "C6619"
			(at 0 0 90)
			(layer "B.SilkS")
			(hide yes)
			(effects
				(font
					(size 1.27 1.27)
				)
				(justify mirror)
			)
		)
		(property "Value" ""
			(at 0 0 90)
			(layer "B.Fab")
			(effects
				(font
					(size 1.27 1.27)
				)
				(justify mirror)
			)
		)
		(duplicate_pad_numbers_are_jumpers no)
		(fp_line
			(start 0.299974 -0.150114)
			(end -0.299974 -0.150114)
			(stroke
				(width 0.1)
				(type default)
			)
			(layer "B.Fab")
		)
		(fp_line
			(start -0.299974 -0.150114)
			(end -0.299974 0.150114)
			(stroke
				(width 0.1)
				(type default)
			)
			(layer "B.Fab")
		)
		(fp_line
			(start 0.299974 0.150114)
			(end 0.299974 -0.150114)
			(stroke
				(width 0.1)
				(type default)
			)
			(layer "B.Fab")
		)
		(fp_line
			(start -0.299974 0.150114)
			(end 0.299974 0.150114)
			(stroke
				(width 0.1)
				(type default)
			)
			(layer "B.Fab")
		)
		(pad "1" smd rect
			(at 0.2667 0 270)
			(size 0.3048 0.381)
			(layers "B.Cu" "B.Mask" "B.Paste")
			(net "P5E_CPU0_P3_TX_BUF_C_DP<11>")
		)
		(pad "2" smd rect
			(at -0.2667 0 270)
			(size 0.3048 0.381)
			(layers "B.Cu" "B.Mask" "B.Paste")
			(net "P5E_CPU0_P3_TX_BUF_DP<11>")
		)
	)
)
